(kicad_pcb
	(version 20260206)
	(generator "pcbnew")
	(generator_version "10.0")
	(general
		(thickness 1.6)
		(legacy_teardrops no)
	)
	(paper "A4")
	(title_block
		(title "04192023_DAF0TMB3IC0_F0TG_MB_C_brd_V02_OCP.brd")
		(comment 1 "Grand Teton / footprints 3407-3412 of 8354")
	)
	(layers
		(0 "F.Cu" signal "TOP")
		(4 "In1.Cu" signal "GND")
		(6 "In2.Cu" signal "IN1")
		(8 "In3.Cu" signal "GND1")
		(10 "In4.Cu" signal "IN2")
		(12 "In5.Cu" signal "GND2")
		(14 "In6.Cu" signal "IN3")
		(16 "In7.Cu" signal "GND3")
		(18 "In8.Cu" signal "VCC")
		(20 "In9.Cu" signal "VCC1")
		(22 "In10.Cu" signal "GND4")
		(24 "In11.Cu" signal "IN4")
		(26 "In12.Cu" signal "GND5")
		(28 "In13.Cu" signal "IN5")
		(30 "In14.Cu" signal "GND6")
		(32 "In15.Cu" signal "IN6")
		(34 "In16.Cu" signal "GND7")
		(2 "B.Cu" signal "BOTTOM")
		(9 "F.Adhes" user "F.Adhesive")
		(11 "B.Adhes" user "B.Adhesive")
		(13 "F.Paste" user "Package Geometry/Pastemask Top")
		(15 "B.Paste" user "Package Geometry/Pastemask Bottom")
		(5 "F.SilkS" user "Ref Des/Silkscreen Top")
		(7 "B.SilkS" user "Ref Des/Silkscreen Bottom")
		(1 "F.Mask" user "Board Geometry/Soldermask Top")
		(3 "B.Mask" user "Board Geometry/Soldermask Bottom")
		(17 "Dwgs.User" user "User.Drawings")
		(19 "Cmts.User" user "User.Comments")
		(21 "Eco1.User" user "User.Eco1")
		(23 "Eco2.User" user "User.Eco2")
		(25 "Edge.Cuts" user "Board Geometry/Outline")
		(27 "Margin" user)
		(31 "F.CrtYd" user "Package Geometry/Place Bound Top")
		(29 "B.CrtYd" user "Package Geometry/Place Bound Bottom")
		(35 "F.Fab" user "Ref Des/Assembly Top")
		(33 "B.Fab" user "Ref Des/Assembly Bottom")
	)
	(footprint ""
		(layer "F.Cu")
		(at 99.015296 -412.931102 90)
		(property "Reference" "R4178"
			(at 0 0 90)
			(layer "F.SilkS")
			(hide yes)
			(effects
				(font
					(size 1.27 1.27)
				)
			)
		)
		(property "Value" ""
			(at 0 0 90)
			(layer "F.Fab")
			(effects
				(font
					(size 1.27 1.27)
				)
			)
		)
		(duplicate_pad_numbers_are_jumpers no)
		(fp_line
			(start 0.7874 -0.4064)
			(end 0.7874 0.4064)
			(stroke
				(width 0.1524)
				(type default)
			)
			(layer "F.SilkS")
		)
		(fp_line
			(start -0.7874 -0.4064)
			(end 0.7874 -0.4064)
			(stroke
				(width 0.1524)
				(type default)
			)
			(layer "F.SilkS")
		)
		(fp_line
			(start 0.7874 0.4064)
			(end -0.7874 0.4064)
			(stroke
				(width 0.1524)
				(type default)
			)
			(layer "F.SilkS")
		)
		(fp_line
			(start -0.7874 0.4064)
			(end -0.7874 -0.4064)
			(stroke
				(width 0.1524)
				(type default)
			)
			(layer "F.SilkS")
		)
		(fp_line
			(start -0.12065 -0.305054)
			(end -0.12065 -0.2794)
			(stroke
				(width 0.1)
				(type default)
			)
			(layer "F.Fab")
		)
		(fp_line
			(start -0.67945 -0.305054)
			(end -0.12065 -0.305054)
			(stroke
				(width 0.1)
				(type default)
			)
			(layer "F.Fab")
		)
		(fp_line
			(start 0.67945 -0.3048)
			(end 0.67945 0.3048)
			(stroke
				(width 0.1)
				(type default)
			)
			(layer "F.Fab")
		)
		(fp_line
			(start 0.12065 -0.3048)
			(end 0.67945 -0.3048)
			(stroke
				(width 0.1)
				(type default)
			)
			(layer "F.Fab")
		)
		(fp_line
			(start 0.12065 -0.2794)
			(end 0.12065 -0.3048)
			(stroke
				(width 0.1)
				(type default)
			)
			(layer "F.Fab")
		)
		(fp_line
			(start -0.12065 -0.2794)
			(end 0.12065 -0.2794)
			(stroke
				(width 0.1)
				(type default)
			)
			(layer "F.Fab")
		)
		(fp_line
			(start 0.120396 0.2794)
			(end -0.12065 0.2794)
			(stroke
				(width 0.1)
				(type default)
			)
			(layer "F.Fab")
		)
		(fp_line
			(start -0.12065 0.2794)
			(end -0.12065 0.3048)
			(stroke
				(width 0.1)
				(type default)
			)
			(layer "F.Fab")
		)
		(fp_line
			(start 0.67945 0.3048)
			(end 0.120396 0.3048)
			(stroke
				(width 0.1)
				(type default)
			)
			(layer "F.Fab")
		)
		(fp_line
			(start 0.120396 0.3048)
			(end 0.120396 0.2794)
			(stroke
				(width 0.1)
				(type default)
			)
			(layer "F.Fab")
		)
		(fp_line
			(start -0.12065 0.3048)
			(end -0.67945 0.3048)
			(stroke
				(width 0.1)
				(type default)
			)
			(layer "F.Fab")
		)
		(fp_line
			(start -0.67945 0.3048)
			(end -0.67945 -0.305054)
			(stroke
				(width 0.1)
				(type default)
			)
			(layer "F.Fab")
		)
		(pad "1" smd circle
			(at -0.40005 0 90)
			(size 0 0)
			(layers "F.Cu" "F.Mask" "F.Paste")
			(net "SMB_LM75_2_3V3AUX_SCL")
		)
		(pad "2" smd circle
			(at 0.40005 0 90)
			(size 0 0)
			(layers "F.Cu" "F.Mask" "F.Paste")
			(net "SMB_LM75_2_3V3AUX_SCL_R1")
		)
	)
	(footprint ""
		(layer "F.Cu")
		(at 276.481794 -94.789498 180)
		(property "Reference" "C1517"
			(at 0 0 180)
			(layer "F.SilkS")
			(hide yes)
			(effects
				(font
					(size 1.27 1.27)
				)
			)
		)
		(property "Value" ""
			(at 0 0 180)
			(layer "F.Fab")
			(effects
				(font
					(size 1.27 1.27)
				)
			)
		)
		(duplicate_pad_numbers_are_jumpers no)
		(fp_line
			(start 0.7874 0.4064)
			(end -0.7874 0.4064)
			(stroke
				(width 0.1524)
				(type default)
			)
			(layer "F.SilkS")
		)
		(fp_line
			(start 0.7874 -0.4064)
			(end 0.7874 0.4064)
			(stroke
				(width 0.1524)
				(type default)
			)
			(layer "F.SilkS")
		)
		(fp_line
			(start -0.7874 0.4064)
			(end -0.7874 -0.4064)
			(stroke
				(width 0.1524)
				(type default)
			)
			(layer "F.SilkS")
		)
		(fp_line
			(start -0.7874 -0.4064)
			(end 0.7874 -0.4064)
			(stroke
				(width 0.1524)
				(type default)
			)
			(layer "F.SilkS")
		)
		(fp_line
			(start 0.67945 0.3048)
			(end 0.120396 0.3048)
			(stroke
				(width 0.1)
				(type default)
			)
			(layer "F.Fab")
		)
		(fp_line
			(start 0.67945 -0.3048)
			(end 0.67945 0.3048)
			(stroke
				(width 0.1)
				(type default)
			)
			(layer "F.Fab")
		)
		(fp_line
			(start 0.12065 -0.2794)
			(end 0.12065 -0.3048)
			(stroke
				(width 0.1)
				(type default)
			)
			(layer "F.Fab")
		)
		(fp_line
			(start 0.12065 -0.3048)
			(end 0.67945 -0.3048)
			(stroke
				(width 0.1)
				(type default)
			)
			(layer "F.Fab")
		)
		(fp_line
			(start 0.120396 0.3048)
			(end 0.120396 0.2794)
			(stroke
				(width 0.1)
				(type default)
			)
			(layer "F.Fab")
		)
		(fp_line
			(start 0.120396 0.2794)
			(end -0.12065 0.2794)
			(stroke
				(width 0.1)
				(type default)
			)
			(layer "F.Fab")
		)
		(fp_line
			(start -0.12065 0.3048)
			(end -0.67945 0.3048)
			(stroke
				(width 0.1)
				(type default)
			)
			(layer "F.Fab")
		)
		(fp_line
			(start -0.12065 0.2794)
			(end -0.12065 0.3048)
			(stroke
				(width 0.1)
				(type default)
			)
			(layer "F.Fab")
		)
		(fp_line
			(start -0.12065 -0.2794)
			(end 0.12065 -0.2794)
			(stroke
				(width 0.1)
				(type default)
			)
			(layer "F.Fab")
		)
		(fp_line
			(start -0.12065 -0.305054)
			(end -0.12065 -0.2794)
			(stroke
				(width 0.1)
				(type default)
			)
			(layer "F.Fab")
		)
		(fp_line
			(start -0.67945 0.3048)
			(end -0.67945 -0.305054)
			(stroke
				(width 0.1)
				(type default)
			)
			(layer "F.Fab")
		)
		(fp_line
			(start -0.67945 -0.305054)
			(end -0.12065 -0.305054)
			(stroke
				(width 0.1)
				(type default)
			)
			(layer "F.Fab")
		)
		(pad "1" smd circle
			(at -0.40005 0 180)
			(size 0 0)
			(layers "F.Cu" "F.Mask" "F.Paste")
			(net "PVDD18_S5_P1")
		)
		(pad "2" smd circle
			(at 0.40005 0 180)
			(size 0 0)
			(layers "F.Cu" "F.Mask" "F.Paste")
			(net "GND")
		)
	)
	(footprint ""
		(layer "F.Cu")
		(at 212.471508 0.002794)
		(property "Reference" "J75"
			(at -4.427728 1.119632 90)
			(unlocked yes)
			(layer "F.SilkS")
			(effects
				(font
					(size 0.7874 0.5842)
					(thickness 0.1524)
				)
				(justify left)
			)
		)
		(property "Value" ""
			(at 0 0 0)
			(layer "F.Fab")
			(effects
				(font
					(size 1.27 1.27)
				)
			)
		)
		(duplicate_pad_numbers_are_jumpers no)
		(fp_line
			(start -1.2192 -2.06756)
			(end 1.2192 -2.06756)
			(stroke
				(width 0.1524)
				(type default)
			)
			(layer "F.SilkS")
		)
		(fp_line
			(start -1.2192 2.06756)
			(end -1.2192 -2.06756)
			(stroke
				(width 0.1524)
				(type default)
			)
			(layer "F.SilkS")
		)
		(fp_line
			(start 1.2192 -2.06756)
			(end 1.2192 2.06756)
			(stroke
				(width 0.1524)
				(type default)
			)
			(layer "F.SilkS")
		)
		(fp_line
			(start 1.2192 2.06756)
			(end -1.2192 2.06756)
			(stroke
				(width 0.1524)
				(type default)
			)
			(layer "F.SilkS")
		)
		(pad "" np_thru_hole circle
			(at -2.8829 -1.27 270)
			(size 1.0414 1.0414)
			(drill 1.0414)
			(layers "*.Cu" "*.Mask")
			(clearance 0.381)
			(thermal_gap 0.381)
		)
		(pad "" np_thru_hole circle
			(at -2.8829 1.27 270)
			(size 1.0414 1.0414)
			(drill 1.0414)
			(layers "*.Cu" "*.Mask")
			(clearance 0.381)
			(thermal_gap 0.381)
		)
		(pad "" np_thru_hole circle
			(at 3.4671 -1.27 270)
			(size 1.0414 1.0414)
			(drill 1.0414)
			(layers "*.Cu" "*.Mask")
			(clearance 0.381)
			(thermal_gap 0.381)
		)
		(pad "" np_thru_hole circle
			(at 3.4671 1.27 270)
			(size 1.0414 1.0414)
			(drill 1.0414)
			(layers "*.Cu" "*.Mask")
			(clearance 0.381)
			(thermal_gap 0.381)
		)
		(pad "1" smd rect
			(at 0.8255 -0.249936 270)
			(size 0.3048 0.508)
			(layers "F.Cu" "F.Mask" "F.Paste")
			(net "DELTA_L_85_10INCH_TOP_DP")
		)
		(pad "2" smd rect
			(at 0.8255 0.249936 270)
			(size 0.3048 0.508)
			(layers "F.Cu" "F.Mask" "F.Paste")
			(net "DELTA_L_85_10INCH_TOP_DN")
		)
		(pad "3" smd circle
			(at 0 0)
			(size 0 0)
			(layers "F.Cu" "F.Mask" "F.Paste")
			(net "DELTA_L_GND_1")
		)
		(zone
			(layer "F.Cu")
			(hatch none 0.5)
			(connect_pads
				(clearance 0)
			)
			(min_thickness 0.25)
			(keepout
				(tracks not_allowed)
				(vias allowed)
				(pads allowed)
				(copperpour not_allowed)
				(footprints allowed)
			)
			(placement
				(enabled no)
				(sheetname "")
			)
			(fill
				(thermal_gap 0.5)
				(thermal_bridge_width 0.5)
				(island_removal_mode 0)
			)
			(polygon
				(pts
					(xy 213.589108 -0.545846) (xy 213.589108 -0.450342) (xy 212.992208 -0.450342) (xy 212.992208 -0.043942)
					(xy 213.589108 -0.043942) (xy 213.589108 0.04953) (xy 212.992208 0.04953) (xy 212.992208 0.45593)
					(xy 213.589108 0.45593) (xy 213.589108 0.551434) (xy 212.890608 0.551434) (xy 212.890608 -0.545846)
				)
			)
		)
		(zone
			(layers "F.Cu" "B.Cu" "In1.Cu" "In2.Cu" "In3.Cu" "In4.Cu" "In5.Cu" "In6.Cu"
				"In7.Cu" "In8.Cu" "In9.Cu" "In10.Cu" "In11.Cu" "In12.Cu" "In13.Cu" "In14.Cu"
				"In15.Cu" "In16.Cu"
			)
			(hatch none 0.5)
			(connect_pads
				(clearance 0)
			)
			(min_thickness 0.25)
			(keepout
				(tracks not_allowed)
				(vias allowed)
				(pads allowed)
				(copperpour not_allowed)
				(footprints allowed)
			)
			(placement
				(enabled no)
				(sheetname "")
			)
			(fill
				(thermal_gap 0.5)
				(thermal_bridge_width 0.5)
				(island_removal_mode 0)
			)
			(polygon
				(pts
					(arc
						(start 210.515708 -1.267206)
						(mid 208.661508 -1.267206)
						(end 210.515708 -1.267206)
					)
				)
			)
		)
		(zone
			(layers "F.Cu" "B.Cu" "In1.Cu" "In2.Cu" "In3.Cu" "In4.Cu" "In5.Cu" "In6.Cu"
				"In7.Cu" "In8.Cu" "In9.Cu" "In10.Cu" "In11.Cu" "In12.Cu" "In13.Cu" "In14.Cu"
				"In15.Cu" "In16.Cu"
			)
			(hatch none 0.5)
			(connect_pads
				(clearance 0)
			)
			(min_thickness 0.25)
			(keepout
				(tracks not_allowed)
				(vias allowed)
				(pads allowed)
				(copperpour not_allowed)
				(footprints allowed)
			)
			(placement
				(enabled no)
				(sheetname "")
			)
			(fill
				(thermal_gap 0.5)
				(thermal_bridge_width 0.5)
				(island_removal_mode 0)
			)
			(polygon
				(pts
					(arc
						(start 210.515708 1.272794)
						(mid 208.661508 1.272794)
						(end 210.515708 1.272794)
					)
				)
			)
		)
		(zone
			(layers "F.Cu" "B.Cu" "In1.Cu" "In2.Cu" "In3.Cu" "In4.Cu" "In5.Cu" "In6.Cu"
				"In7.Cu" "In8.Cu" "In9.Cu" "In10.Cu" "In11.Cu" "In12.Cu" "In13.Cu" "In14.Cu"
				"In15.Cu" "In16.Cu"
			)
			(hatch none 0.5)
			(connect_pads
				(clearance 0)
			)
			(min_thickness 0.25)
			(keepout
				(tracks not_allowed)
				(vias allowed)
				(pads allowed)
				(copperpour not_allowed)
				(footprints allowed)
			)
			(placement
				(enabled no)
				(sheetname "")
			)
			(fill
				(thermal_gap 0.5)
				(thermal_bridge_width 0.5)
				(island_removal_mode 0)
			)
			(polygon
				(pts
					(arc
						(start 216.865708 -1.267206)
						(mid 215.011508 -1.267206)
						(end 216.865708 -1.267206)
					)
				)
			)
		)
		(zone
			(layers "F.Cu" "B.Cu" "In1.Cu" "In2.Cu" "In3.Cu" "In4.Cu" "In5.Cu" "In6.Cu"
				"In7.Cu" "In8.Cu" "In9.Cu" "In10.Cu" "In11.Cu" "In12.Cu" "In13.Cu" "In14.Cu"
				"In15.Cu" "In16.Cu"
			)
			(hatch none 0.5)
			(connect_pads
				(clearance 0)
			)
			(min_thickness 0.25)
			(keepout
				(tracks not_allowed)
				(vias allowed)
				(pads allowed)
				(copperpour not_allowed)
				(footprints allowed)
			)
			(placement
				(enabled no)
				(sheetname "")
			)
			(fill
				(thermal_gap 0.5)
				(thermal_bridge_width 0.5)
				(island_removal_mode 0)
			)
			(polygon
				(pts
					(arc
						(start 216.865708 1.272794)
						(mid 215.011508 1.272794)
						(end 216.865708 1.272794)
					)
				)
			)
		)
	)
	(footprint ""
		(layer "F.Cu")
		(at 72.6948 -386.7912 90)
		(property "Reference" "R6715"
			(at 0 0 90)
			(layer "F.SilkS")
			(hide yes)
			(effects
				(font
					(size 1.27 1.27)
				)
			)
		)
		(property "Value" ""
			(at 0 0 90)
			(layer "F.Fab")
			(effects
				(font
					(size 1.27 1.27)
				)
			)
		)
		(duplicate_pad_numbers_are_jumpers no)
		(fp_line
			(start 0.32512 -0.175006)
			(end 0.32512 0.175006)
			(stroke
				(width 0.1)
				(type default)
			)
			(layer "F.Fab")
		)
		(fp_line
			(start -0.32512 -0.175006)
			(end 0.32512 -0.175006)
			(stroke
				(width 0.1)
				(type default)
			)
			(layer "F.Fab")
		)
		(fp_line
			(start 0.32512 0.175006)
			(end -0.32512 0.175006)
			(stroke
				(width 0.1)
				(type default)
			)
			(layer "F.Fab")
		)
		(fp_line
			(start -0.32512 0.175006)
			(end -0.32512 -0.175006)
			(stroke
				(width 0.1)
				(type default)
			)
			(layer "F.Fab")
		)
		(pad "1" smd rect
			(at -0.2667 0 90)
			(size 0.3048 0.381)
			(layers "F.Cu" "F.Mask" "F.Paste")
			(net "RT_CPU1_P0_ADDR2")
		)
		(pad "2" smd rect
			(at 0.2667 0 270)
			(size 0.3048 0.381)
			(layers "F.Cu" "F.Mask" "F.Paste")
			(net "GND")
		)
	)
	(footprint ""
		(layer "F.Cu")
		(at 240.096802 -70.143624 90)
		(property "Reference" "R999"
			(at 0 0 90)
			(layer "F.SilkS")
			(hide yes)
			(effects
				(font
					(size 1.27 1.27)
				)
			)
		)
		(property "Value" ""
			(at 0 0 90)
			(layer "F.Fab")
			(effects
				(font
					(size 1.27 1.27)
				)
			)
		)
		(duplicate_pad_numbers_are_jumpers no)
		(fp_line
			(start 0.7874 -0.4064)
			(end 0.7874 0.4064)
			(stroke
				(width 0.1524)
				(type default)
			)
			(layer "F.SilkS")
		)
		(fp_line
			(start -0.7874 -0.4064)
			(end 0.7874 -0.4064)
			(stroke
				(width 0.1524)
				(type default)
			)
			(layer "F.SilkS")
		)
		(fp_line
			(start 0.7874 0.4064)
			(end -0.7874 0.4064)
			(stroke
				(width 0.1524)
				(type default)
			)
			(layer "F.SilkS")
		)
		(fp_line
			(start -0.7874 0.4064)
			(end -0.7874 -0.4064)
			(stroke
				(width 0.1524)
				(type default)
			)
			(layer "F.SilkS")
		)
		(fp_line
			(start -0.12065 -0.305054)
			(end -0.12065 -0.2794)
			(stroke
				(width 0.1)
				(type default)
			)
			(layer "F.Fab")
		)
		(fp_line
			(start -0.67945 -0.305054)
			(end -0.12065 -0.305054)
			(stroke
				(width 0.1)
				(type default)
			)
			(layer "F.Fab")
		)
		(fp_line
			(start 0.67945 -0.3048)
			(end 0.67945 0.3048)
			(stroke
				(width 0.1)
				(type default)
			)
			(layer "F.Fab")
		)
		(fp_line
			(start 0.12065 -0.3048)
			(end 0.67945 -0.3048)
			(stroke
				(width 0.1)
				(type default)
			)
			(layer "F.Fab")
		)
		(fp_line
			(start 0.12065 -0.2794)
			(end 0.12065 -0.3048)
			(stroke
				(width 0.1)
				(type default)
			)
			(layer "F.Fab")
		)
		(fp_line
			(start -0.12065 -0.2794)
			(end 0.12065 -0.2794)
			(stroke
				(width 0.1)
				(type default)
			)
			(layer "F.Fab")
		)
		(fp_line
			(start 0.120396 0.2794)
			(end -0.12065 0.2794)
			(stroke
				(width 0.1)
				(type default)
			)
			(layer "F.Fab")
		)
		(fp_line
			(start -0.12065 0.2794)
			(end -0.12065 0.3048)
			(stroke
				(width 0.1)
				(type default)
			)
			(layer "F.Fab")
		)
		(fp_line
			(start 0.67945 0.3048)
			(end 0.120396 0.3048)
			(stroke
				(width 0.1)
				(type default)
			)
			(layer "F.Fab")
		)
		(fp_line
			(start 0.120396 0.3048)
			(end 0.120396 0.2794)
			(stroke
				(width 0.1)
				(type default)
			)
			(layer "F.Fab")
		)
		(fp_line
			(start -0.12065 0.3048)
			(end -0.67945 0.3048)
			(stroke
				(width 0.1)
				(type default)
			)
			(layer "F.Fab")
		)
		(fp_line
			(start -0.67945 0.3048)
			(end -0.67945 -0.305054)
			(stroke
				(width 0.1)
				(type default)
			)
			(layer "F.Fab")
		)
		(pad "1" smd circle
			(at -0.40005 0 90)
			(size 0 0)
			(layers "F.Cu" "F.Mask" "F.Paste")
			(net "FM_LED_ACTIVE_E1S_0_R")
		)
		(pad "2" smd circle
			(at 0.40005 0 90)
			(size 0 0)
			(layers "F.Cu" "F.Mask" "F.Paste")
			(net "GND")
		)
	)
	(footprint ""
		(layer "F.Cu")
		(at 314.567316 -110.55477 180)
		(property "Reference" "R4"
			(at 0 0 180)
			(layer "F.SilkS")
			(hide yes)
			(effects
				(font
					(size 1.27 1.27)
				)
			)
		)
		(property "Value" ""
			(at 0 0 180)
			(layer "F.Fab")
			(effects
				(font
					(size 1.27 1.27)
				)
			)
		)
		(duplicate_pad_numbers_are_jumpers no)
		(fp_line
			(start 0.7874 0.4064)
			(end -0.7874 0.4064)
			(stroke
				(width 0.1524)
				(type default)
			)
			(layer "F.SilkS")
		)
		(fp_line
			(start 0.7874 -0.4064)
			(end 0.7874 0.4064)
			(stroke
				(width 0.1524)
				(type default)
			)
			(layer "F.SilkS")
		)
		(fp_line
			(start -0.7874 0.4064)
			(end -0.7874 -0.4064)
			(stroke
				(width 0.1524)
				(type default)
			)
			(layer "F.SilkS")
		)
		(fp_line
			(start -0.7874 -0.4064)
			(end 0.7874 -0.4064)
			(stroke
				(width 0.1524)
				(type default)
			)
			(layer "F.SilkS")
		)
		(fp_line
			(start 0.67945 0.3048)
			(end 0.120396 0.3048)
			(stroke
				(width 0.1)
				(type default)
			)
			(layer "F.Fab")
		)
		(fp_line
			(start 0.67945 -0.3048)
			(end 0.67945 0.3048)
			(stroke
				(width 0.1)
				(type default)
			)
			(layer "F.Fab")
		)
		(fp_line
			(start 0.12065 -0.2794)
			(end 0.12065 -0.3048)
			(stroke
				(width 0.1)
				(type default)
			)
			(layer "F.Fab")
		)
		(fp_line
			(start 0.12065 -0.3048)
			(end 0.67945 -0.3048)
			(stroke
				(width 0.1)
				(type default)
			)
			(layer "F.Fab")
		)
		(fp_line
			(start 0.120396 0.3048)
			(end 0.120396 0.2794)
			(stroke
				(width 0.1)
				(type default)
			)
			(layer "F.Fab")
		)
		(fp_line
			(start 0.120396 0.2794)
			(end -0.12065 0.2794)
			(stroke
				(width 0.1)
				(type default)
			)
			(layer "F.Fab")
		)
		(fp_line
			(start -0.12065 0.3048)
			(end -0.67945 0.3048)
			(stroke
				(width 0.1)
				(type default)
			)
			(layer "F.Fab")
		)
		(fp_line
			(start -0.12065 0.2794)
			(end -0.12065 0.3048)
			(stroke
				(width 0.1)
				(type default)
			)
			(layer "F.Fab")
		)
		(fp_line
			(start -0.12065 -0.2794)
			(end 0.12065 -0.2794)
			(stroke
				(width 0.1)
				(type default)
			)
			(layer "F.Fab")
		)
		(fp_line
			(start -0.12065 -0.305054)
			(end -0.12065 -0.2794)
			(stroke
				(width 0.1)
				(type default)
			)
			(layer "F.Fab")
		)
		(fp_line
			(start -0.67945 0.3048)
			(end -0.67945 -0.305054)
			(stroke
				(width 0.1)
				(type default)
			)
			(layer "F.Fab")
		)
		(fp_line
			(start -0.67945 -0.305054)
			(end -0.12065 -0.305054)
			(stroke
				(width 0.1)
				(type default)
			)
			(layer "F.Fab")
		)
		(pad "1" smd circle
			(at -0.40005 0 180)
			(size 0 0)
			(layers "F.Cu" "F.Mask" "F.Paste")
			(net "P3V3_AUX")
		)
		(pad "2" smd circle
			(at 0.40005 0 180)
			(size 0 0)
			(layers "F.Cu" "F.Mask" "F.Paste")
			(net "SMB_CPU_FRU_3V3AUX_SCL")
		)
	)
)
